(kicad_pcb
	(version 20260206)
	(generator "pcbnew")
	(generator_version "10.0")
	(general
		(thickness 1.6)
		(legacy_teardrops no)
	)
	(paper "A4")
	(title_block
		(title "01162023_DA0F0TEBIF0_F0T_Expander_BD_F_brd_V02_OCP.brd")
		(comment 1 "Grand Teton / footprints 377-382 of 9728")
	)
	(layers
		(0 "F.Cu" signal "TOP")
		(4 "In1.Cu" signal "GND")
		(6 "In2.Cu" signal "VCC")
		(8 "In3.Cu" signal "VCC1")
		(10 "In4.Cu" signal "GND1")
		(12 "In5.Cu" signal "IN1")
		(14 "In6.Cu" signal "GND2")
		(16 "In7.Cu" signal "IN2")
		(18 "In8.Cu" signal "GND3")
		(20 "In9.Cu" signal "IN3")
		(22 "In10.Cu" signal "GND4")
		(24 "In11.Cu" signal "IN4")
		(26 "In12.Cu" signal "GND5")
		(28 "In13.Cu" signal "IN5")
		(30 "In14.Cu" signal "GND6")
		(32 "In15.Cu" signal "IN6")
		(34 "In16.Cu" signal "GND7")
		(2 "B.Cu" signal "BOTTOM")
		(9 "F.Adhes" user "F.Adhesive")
		(11 "B.Adhes" user "B.Adhesive")
		(13 "F.Paste" user "Package Geometry/Pastemask Top")
		(15 "B.Paste" user "Package Geometry/Pastemask Bottom")
		(5 "F.SilkS" user "Ref Des/Silkscreen Top")
		(7 "B.SilkS" user "Ref Des/Silkscreen Bottom")
		(1 "F.Mask" user "Board Geometry/Soldermask Top")
		(3 "B.Mask" user "Board Geometry/Soldermask Bottom")
		(17 "Dwgs.User" user "User.Drawings")
		(19 "Cmts.User" user "User.Comments")
		(21 "Eco1.User" user "User.Eco1")
		(23 "Eco2.User" user "User.Eco2")
		(25 "Edge.Cuts" user "Board Geometry/Outline")
		(27 "Margin" user)
		(31 "F.CrtYd" user "Package Geometry/Place Bound Top")
		(29 "B.CrtYd" user "Package Geometry/Place Bound Bottom")
		(35 "F.Fab" user "Ref Des/Assembly Top")
		(33 "B.Fab" user "Ref Des/Assembly Bottom")
	)
	(footprint ""
		(layer "F.Cu")
		(at 426.543724 -46.90491)
		(property "Reference" "R662"
			(at 0 0 0)
			(layer "F.SilkS")
			(hide yes)
			(effects
				(font
					(size 1.27 1.27)
				)
			)
		)
		(property "Value" ""
			(at 0 0 0)
			(layer "F.Fab")
			(effects
				(font
					(size 1.27 1.27)
				)
			)
		)
		(duplicate_pad_numbers_are_jumpers no)
		(fp_line
			(start -0.7874 -0.4064)
			(end 0.7874 -0.4064)
			(stroke
				(width 0.1524)
				(type default)
			)
			(layer "F.SilkS")
		)
		(fp_line
			(start -0.7874 0.4064)
			(end -0.7874 -0.4064)
			(stroke
				(width 0.1524)
				(type default)
			)
			(layer "F.SilkS")
		)
		(fp_line
			(start 0.7874 -0.4064)
			(end 0.7874 0.4064)
			(stroke
				(width 0.1524)
				(type default)
			)
			(layer "F.SilkS")
		)
		(fp_line
			(start 0.7874 0.4064)
			(end -0.7874 0.4064)
			(stroke
				(width 0.1524)
				(type default)
			)
			(layer "F.SilkS")
		)
		(fp_line
			(start -0.67945 -0.305054)
			(end -0.12065 -0.305054)
			(stroke
				(width 0.1)
				(type default)
			)
			(layer "F.Fab")
		)
		(fp_line
			(start -0.67945 0.3048)
			(end -0.67945 -0.305054)
			(stroke
				(width 0.1)
				(type default)
			)
			(layer "F.Fab")
		)
		(fp_line
			(start -0.12065 -0.305054)
			(end -0.12065 -0.2794)
			(stroke
				(width 0.1)
				(type default)
			)
			(layer "F.Fab")
		)
		(fp_line
			(start -0.12065 -0.2794)
			(end 0.12065 -0.2794)
			(stroke
				(width 0.1)
				(type default)
			)
			(layer "F.Fab")
		)
		(fp_line
			(start -0.12065 0.2794)
			(end -0.12065 0.3048)
			(stroke
				(width 0.1)
				(type default)
			)
			(layer "F.Fab")
		)
		(fp_line
			(start -0.12065 0.3048)
			(end -0.67945 0.3048)
			(stroke
				(width 0.1)
				(type default)
			)
			(layer "F.Fab")
		)
		(fp_line
			(start 0.120396 0.2794)
			(end -0.12065 0.2794)
			(stroke
				(width 0.1)
				(type default)
			)
			(layer "F.Fab")
		)
		(fp_line
			(start 0.120396 0.3048)
			(end 0.120396 0.2794)
			(stroke
				(width 0.1)
				(type default)
			)
			(layer "F.Fab")
		)
		(fp_line
			(start 0.12065 -0.3048)
			(end 0.67945 -0.3048)
			(stroke
				(width 0.1)
				(type default)
			)
			(layer "F.Fab")
		)
		(fp_line
			(start 0.12065 -0.2794)
			(end 0.12065 -0.3048)
			(stroke
				(width 0.1)
				(type default)
			)
			(layer "F.Fab")
		)
		(fp_line
			(start 0.67945 -0.3048)
			(end 0.67945 0.3048)
			(stroke
				(width 0.1)
				(type default)
			)
			(layer "F.Fab")
		)
		(fp_line
			(start 0.67945 0.3048)
			(end 0.120396 0.3048)
			(stroke
				(width 0.1)
				(type default)
			)
			(layer "F.Fab")
		)
		(pad "1" smd circle
			(at -0.40005 0)
			(size 0 0)
			(layers "F.Cu" "F.Mask" "F.Paste")
			(net "SSD14_ADC_ALERT_N")
		)
		(pad "2" smd circle
			(at 0.40005 0)
			(size 0 0)
			(layers "F.Cu" "F.Mask" "F.Paste")
			(net "SSD_8_15_ADC_ALERT_N")
		)
	)
	(footprint ""
		(layer "F.Cu")
		(at 16.706596 -255.046734 -90)
		(property "Reference" "R6465"
			(at 0 0 270)
			(layer "F.SilkS")
			(hide yes)
			(effects
				(font
					(size 1.27 1.27)
				)
			)
		)
		(property "Value" ""
			(at 0 0 270)
			(layer "F.Fab")
			(effects
				(font
					(size 1.27 1.27)
				)
			)
		)
		(duplicate_pad_numbers_are_jumpers no)
		(fp_line
			(start -0.7874 0.4064)
			(end -0.7874 -0.4064)
			(stroke
				(width 0.1524)
				(type default)
			)
			(layer "F.SilkS")
		)
		(fp_line
			(start 0.7874 0.4064)
			(end -0.7874 0.4064)
			(stroke
				(width 0.1524)
				(type default)
			)
			(layer "F.SilkS")
		)
		(fp_line
			(start -0.7874 -0.4064)
			(end 0.7874 -0.4064)
			(stroke
				(width 0.1524)
				(type default)
			)
			(layer "F.SilkS")
		)
		(fp_line
			(start 0.7874 -0.4064)
			(end 0.7874 0.4064)
			(stroke
				(width 0.1524)
				(type default)
			)
			(layer "F.SilkS")
		)
		(fp_line
			(start -0.67945 0.3048)
			(end -0.67945 -0.305054)
			(stroke
				(width 0.1)
				(type default)
			)
			(layer "F.Fab")
		)
		(fp_line
			(start -0.12065 0.3048)
			(end -0.67945 0.3048)
			(stroke
				(width 0.1)
				(type default)
			)
			(layer "F.Fab")
		)
		(fp_line
			(start 0.120396 0.3048)
			(end 0.120396 0.2794)
			(stroke
				(width 0.1)
				(type default)
			)
			(layer "F.Fab")
		)
		(fp_line
			(start 0.67945 0.3048)
			(end 0.120396 0.3048)
			(stroke
				(width 0.1)
				(type default)
			)
			(layer "F.Fab")
		)
		(fp_line
			(start -0.12065 0.2794)
			(end -0.12065 0.3048)
			(stroke
				(width 0.1)
				(type default)
			)
			(layer "F.Fab")
		)
		(fp_line
			(start 0.120396 0.2794)
			(end -0.12065 0.2794)
			(stroke
				(width 0.1)
				(type default)
			)
			(layer "F.Fab")
		)
		(fp_line
			(start -0.12065 -0.2794)
			(end 0.12065 -0.2794)
			(stroke
				(width 0.1)
				(type default)
			)
			(layer "F.Fab")
		)
		(fp_line
			(start 0.12065 -0.2794)
			(end 0.12065 -0.3048)
			(stroke
				(width 0.1)
				(type default)
			)
			(layer "F.Fab")
		)
		(fp_line
			(start 0.12065 -0.3048)
			(end 0.67945 -0.3048)
			(stroke
				(width 0.1)
				(type default)
			)
			(layer "F.Fab")
		)
		(fp_line
			(start 0.67945 -0.3048)
			(end 0.67945 0.3048)
			(stroke
				(width 0.1)
				(type default)
			)
			(layer "F.Fab")
		)
		(fp_line
			(start -0.67945 -0.305054)
			(end -0.12065 -0.305054)
			(stroke
				(width 0.1)
				(type default)
			)
			(layer "F.Fab")
		)
		(fp_line
			(start -0.12065 -0.305054)
			(end -0.12065 -0.2794)
			(stroke
				(width 0.1)
				(type default)
			)
			(layer "F.Fab")
		)
		(pad "1" smd circle
			(at -0.40005 0 270)
			(size 0 0)
			(layers "F.Cu" "F.Mask" "F.Paste")
			(net "P1V25_SERDES_VDDPLL_PEX0")
		)
		(pad "2" smd circle
			(at 0.40005 0 270)
			(size 0 0)
			(layers "F.Cu" "F.Mask" "F.Paste")
			(net "P1V25_SERDES_VDDPLL_PEX0_C4")
		)
	)
	(footprint ""
		(layer "F.Cu")
		(at 376.312684 -88.8238)
		(property "Reference" "R1743"
			(at 0 0 0)
			(layer "F.SilkS")
			(hide yes)
			(effects
				(font
					(size 1.27 1.27)
				)
			)
		)
		(property "Value" ""
			(at 0 0 0)
			(layer "F.Fab")
			(effects
				(font
					(size 1.27 1.27)
				)
			)
		)
		(duplicate_pad_numbers_are_jumpers no)
		(fp_line
			(start -0.7874 -0.4064)
			(end 0.7874 -0.4064)
			(stroke
				(width 0.1524)
				(type default)
			)
			(layer "F.SilkS")
		)
		(fp_line
			(start -0.7874 0.4064)
			(end -0.7874 -0.4064)
			(stroke
				(width 0.1524)
				(type default)
			)
			(layer "F.SilkS")
		)
		(fp_line
			(start 0.7874 -0.4064)
			(end 0.7874 0.4064)
			(stroke
				(width 0.1524)
				(type default)
			)
			(layer "F.SilkS")
		)
		(fp_line
			(start 0.7874 0.4064)
			(end -0.7874 0.4064)
			(stroke
				(width 0.1524)
				(type default)
			)
			(layer "F.SilkS")
		)
		(fp_line
			(start -0.67945 -0.305054)
			(end -0.12065 -0.305054)
			(stroke
				(width 0.1)
				(type default)
			)
			(layer "F.Fab")
		)
		(fp_line
			(start -0.67945 0.3048)
			(end -0.67945 -0.305054)
			(stroke
				(width 0.1)
				(type default)
			)
			(layer "F.Fab")
		)
		(fp_line
			(start -0.12065 -0.305054)
			(end -0.12065 -0.2794)
			(stroke
				(width 0.1)
				(type default)
			)
			(layer "F.Fab")
		)
		(fp_line
			(start -0.12065 -0.2794)
			(end 0.12065 -0.2794)
			(stroke
				(width 0.1)
				(type default)
			)
			(layer "F.Fab")
		)
		(fp_line
			(start -0.12065 0.2794)
			(end -0.12065 0.3048)
			(stroke
				(width 0.1)
				(type default)
			)
			(layer "F.Fab")
		)
		(fp_line
			(start -0.12065 0.3048)
			(end -0.67945 0.3048)
			(stroke
				(width 0.1)
				(type default)
			)
			(layer "F.Fab")
		)
		(fp_line
			(start 0.120396 0.2794)
			(end -0.12065 0.2794)
			(stroke
				(width 0.1)
				(type default)
			)
			(layer "F.Fab")
		)
		(fp_line
			(start 0.120396 0.3048)
			(end 0.120396 0.2794)
			(stroke
				(width 0.1)
				(type default)
			)
			(layer "F.Fab")
		)
		(fp_line
			(start 0.12065 -0.3048)
			(end 0.67945 -0.3048)
			(stroke
				(width 0.1)
				(type default)
			)
			(layer "F.Fab")
		)
		(fp_line
			(start 0.12065 -0.2794)
			(end 0.12065 -0.3048)
			(stroke
				(width 0.1)
				(type default)
			)
			(layer "F.Fab")
		)
		(fp_line
			(start 0.67945 -0.3048)
			(end 0.67945 0.3048)
			(stroke
				(width 0.1)
				(type default)
			)
			(layer "F.Fab")
		)
		(fp_line
			(start 0.67945 0.3048)
			(end 0.120396 0.3048)
			(stroke
				(width 0.1)
				(type default)
			)
			(layer "F.Fab")
		)
		(pad "1" smd circle
			(at -0.40005 0)
			(size 0 0)
			(layers "F.Cu" "F.Mask" "F.Paste")
			(net "P3V3_AUX")
		)
		(pad "2" smd circle
			(at 0.40005 0)
			(size 0 0)
			(layers "F.Cu" "F.Mask" "F.Paste")
			(net "SMB_BIC_I2C6_MUX_NIC_ADC_R_SDA")
		)
	)
	(footprint ""
		(layer "F.Cu")
		(at 226.977702 -258.012184 -90)
		(property "Reference" "R6500"
			(at 0 0 270)
			(layer "F.SilkS")
			(hide yes)
			(effects
				(font
					(size 1.27 1.27)
				)
			)
		)
		(property "Value" ""
			(at 0 0 270)
			(layer "F.Fab")
			(effects
				(font
					(size 1.27 1.27)
				)
			)
		)
		(duplicate_pad_numbers_are_jumpers no)
		(fp_line
			(start -0.7874 0.4064)
			(end -0.7874 -0.4064)
			(stroke
				(width 0.1524)
				(type default)
			)
			(layer "F.SilkS")
		)
		(fp_line
			(start 0.7874 0.4064)
			(end -0.7874 0.4064)
			(stroke
				(width 0.1524)
				(type default)
			)
			(layer "F.SilkS")
		)
		(fp_line
			(start -0.7874 -0.4064)
			(end 0.7874 -0.4064)
			(stroke
				(width 0.1524)
				(type default)
			)
			(layer "F.SilkS")
		)
		(fp_line
			(start 0.7874 -0.4064)
			(end 0.7874 0.4064)
			(stroke
				(width 0.1524)
				(type default)
			)
			(layer "F.SilkS")
		)
		(fp_line
			(start -0.67945 0.3048)
			(end -0.67945 -0.305054)
			(stroke
				(width 0.1)
				(type default)
			)
			(layer "F.Fab")
		)
		(fp_line
			(start -0.12065 0.3048)
			(end -0.67945 0.3048)
			(stroke
				(width 0.1)
				(type default)
			)
			(layer "F.Fab")
		)
		(fp_line
			(start 0.120396 0.3048)
			(end 0.120396 0.2794)
			(stroke
				(width 0.1)
				(type default)
			)
			(layer "F.Fab")
		)
		(fp_line
			(start 0.67945 0.3048)
			(end 0.120396 0.3048)
			(stroke
				(width 0.1)
				(type default)
			)
			(layer "F.Fab")
		)
		(fp_line
			(start -0.12065 0.2794)
			(end -0.12065 0.3048)
			(stroke
				(width 0.1)
				(type default)
			)
			(layer "F.Fab")
		)
		(fp_line
			(start 0.120396 0.2794)
			(end -0.12065 0.2794)
			(stroke
				(width 0.1)
				(type default)
			)
			(layer "F.Fab")
		)
		(fp_line
			(start -0.12065 -0.2794)
			(end 0.12065 -0.2794)
			(stroke
				(width 0.1)
				(type default)
			)
			(layer "F.Fab")
		)
		(fp_line
			(start 0.12065 -0.2794)
			(end 0.12065 -0.3048)
			(stroke
				(width 0.1)
				(type default)
			)
			(layer "F.Fab")
		)
		(fp_line
			(start 0.12065 -0.3048)
			(end 0.67945 -0.3048)
			(stroke
				(width 0.1)
				(type default)
			)
			(layer "F.Fab")
		)
		(fp_line
			(start 0.67945 -0.3048)
			(end 0.67945 0.3048)
			(stroke
				(width 0.1)
				(type default)
			)
			(layer "F.Fab")
		)
		(fp_line
			(start -0.67945 -0.305054)
			(end -0.12065 -0.305054)
			(stroke
				(width 0.1)
				(type default)
			)
			(layer "F.Fab")
		)
		(fp_line
			(start -0.12065 -0.305054)
			(end -0.12065 -0.2794)
			(stroke
				(width 0.1)
				(type default)
			)
			(layer "F.Fab")
		)
		(pad "1" smd circle
			(at -0.40005 0 270)
			(size 0 0)
			(layers "F.Cu" "F.Mask" "F.Paste")
			(net "P1V25_SERDES_VDDPLL_PEX1")
		)
		(pad "2" smd circle
			(at 0.40005 0 270)
			(size 0 0)
			(layers "F.Cu" "F.Mask" "F.Paste")
			(net "P1V25_SERDES_VDDPLL_PEX1_C7")
		)
	)
	(footprint ""
		(layer "F.Cu")
		(at 410.184092 -350.098614 90)
		(property "Reference" "C2440"
			(at 0 0 90)
			(layer "F.SilkS")
			(hide yes)
			(effects
				(font
					(size 1.27 1.27)
				)
			)
		)
		(property "Value" ""
			(at 0 0 90)
			(layer "F.Fab")
			(effects
				(font
					(size 1.27 1.27)
				)
			)
		)
		(duplicate_pad_numbers_are_jumpers no)
		(fp_line
			(start 0.299974 -0.150114)
			(end 0.299974 0.150114)
			(stroke
				(width 0.1)
				(type default)
			)
			(layer "F.Fab")
		)
		(fp_line
			(start -0.299974 -0.150114)
			(end 0.299974 -0.150114)
			(stroke
				(width 0.1)
				(type default)
			)
			(layer "F.Fab")
		)
		(fp_line
			(start 0.299974 0.150114)
			(end -0.299974 0.150114)
			(stroke
				(width 0.1)
				(type default)
			)
			(layer "F.Fab")
		)
		(fp_line
			(start -0.299974 0.150114)
			(end -0.299974 -0.150114)
			(stroke
				(width 0.1)
				(type default)
			)
			(layer "F.Fab")
		)
		(pad "1" smd rect
			(at -0.2667 0 90)
			(size 0.3048 0.381)
			(layers "F.Cu" "F.Mask" "F.Paste")
			(net "P5E_PEX3_STN4_TX_DN<79>")
		)
		(pad "2" smd rect
			(at 0.2667 0 90)
			(size 0.3048 0.381)
			(layers "F.Cu" "F.Mask" "F.Paste")
			(net "P5E_PEX3_STN4_TX_C_DN<79>")
		)
	)
	(footprint ""
		(layer "F.Cu")
		(at 317.51524 -20.72513)
		(property "Reference" "H122"
			(at 1.556512 -2.603754 0)
			(unlocked yes)
			(layer "B.SilkS")
			(effects
				(font
					(size 0.7874 0.5842)
					(thickness 0.1524)
				)
				(justify left mirror)
			)
		)
		(property "Value" ""
			(at 0 0 0)
			(layer "F.Fab")
			(effects
				(font
					(size 1.27 1.27)
				)
			)
		)
		(duplicate_pad_numbers_are_jumpers no)
		(pad "1" thru_hole rect
			(at 0 0)
			(size 4.2164 5.0038)
			(drill 2.0066
				(offset 0.099822 0)
			)
			(layers "*.Cu" "*.Mask")
			(remove_unused_layers no)
			(net "Net_8541")
			(clearance -0.8509)
			(padstack
				(mode front_inner_back)
				(layer "Inner"
					(shape circle)
					(size 4.0132 4.0132)
					(clearance -0.7493)
				)
				(layer "B.Cu"
					(shape circle)
					(size 4.0132 4.0132)
					(clearance -0.7493)
				)
			)
		)
	)
)
